# T6G (Grand Teton) — schematic netlist excerpt (pin names and nets, part order shuffled) for the footprints in the layout excerpt that follows; sources: Cadence DE-HDL packaged netlist, KiCad conversion of 04192023_DAF0TMB3IC0_F0TG_MB_C_brd_V02_OCP.brd

PC6007  Q_CAP  0.1UF 25V 10% X7R  pkg 0402  page 215 : A = P12V_AUX ; B = GND
PC434_IOP1_2  Q_CAP  2.2UF 10V 10% X6S  pkg C0402  page 222 : A = PVDDCR_CPU1_P1_PVCC ; B = GND

(kicad_pcb
	(version 20260206)
	(generator "pcbnew")
	(generator_version "10.0")
	(general
		(thickness 1.6)
		(legacy_teardrops no)
	)
	(paper "A4")
	(title_block
		(title "04192023_DAF0TMB3IC0_F0TG_MB_C_brd_V02_OCP.brd")
		(comment 1 "Grand Teton / footprints 4128-4129 of 8354")
	)
	(layers
		(0 "F.Cu" signal "TOP")
		(4 "In1.Cu" signal "GND")
		(6 "In2.Cu" signal "IN1")
		(8 "In3.Cu" signal "GND1")
		(10 "In4.Cu" signal "IN2")
		(12 "In5.Cu" signal "GND2")
		(14 "In6.Cu" signal "IN3")
		(16 "In7.Cu" signal "GND3")
		(18 "In8.Cu" signal "VCC")
		(20 "In9.Cu" signal "VCC1")
		(22 "In10.Cu" signal "GND4")
		(24 "In11.Cu" signal "IN4")
		(26 "In12.Cu" signal "GND5")
		(28 "In13.Cu" signal "IN5")
		(30 "In14.Cu" signal "GND6")
		(32 "In15.Cu" signal "IN6")
		(34 "In16.Cu" signal "GND7")
		(2 "B.Cu" signal "BOTTOM")
		(9 "F.Adhes" user "F.Adhesive")
		(11 "B.Adhes" user "B.Adhesive")
		(13 "F.Paste" user "Package Geometry/Pastemask Top")
		(15 "B.Paste" user "Package Geometry/Pastemask Bottom")
		(5 "F.SilkS" user "Ref Des/Silkscreen Top")
		(7 "B.SilkS" user "Ref Des/Silkscreen Bottom")
		(1 "F.Mask" user "Board Geometry/Soldermask Top")
		(3 "B.Mask" user "Board Geometry/Soldermask Bottom")
		(17 "Dwgs.User" user "User.Drawings")
		(19 "Cmts.User" user "User.Comments")
		(21 "Eco1.User" user "User.Eco1")
		(23 "Eco2.User" user "User.Eco2")
		(25 "Edge.Cuts" user "Board Geometry/Outline")
		(27 "Margin" user)
		(31 "F.CrtYd" user "Package Geometry/Place Bound Top")
		(29 "B.CrtYd" user "Package Geometry/Place Bound Bottom")
		(35 "F.Fab" user "Ref Des/Assembly Top")
		(33 "B.Fab" user "Ref Des/Assembly Bottom")
	)
	(footprint ""
		(layer "F.Cu")
		(at 41.503854 -346.719398 -90)
		(property "Reference" "PC434_IOP1_2"
			(at 0 0 270)
			(layer "F.SilkS")
			(hide yes)
			(effects
				(font
					(size 1.27 1.27)
				)
			)
		)
		(property "Value" ""
			(at 0 0 270)
			(layer "F.Fab")
			(effects
				(font
					(size 1.27 1.27)
				)
			)
		)
		(duplicate_pad_numbers_are_jumpers no)
		(fp_line
			(start -0.7874 0.4064)
			(end -0.7874 -0.4064)
			(stroke
				(width 0.1524)
				(type default)
			)
			(layer "F.SilkS")
		)
		(fp_line
			(start 0.7874 0.4064)
			(end -0.7874 0.4064)
			(stroke
				(width 0.1524)
				(type default)
			)
			(layer "F.SilkS")
		)
		(fp_line
			(start -0.7874 -0.4064)
			(end 0.7874 -0.4064)
			(stroke
				(width 0.1524)
				(type default)
			)
			(layer "F.SilkS")
		)
		(fp_line
			(start 0.7874 -0.4064)
			(end 0.7874 0.4064)
			(stroke
				(width 0.1524)
				(type default)
			)
			(layer "F.SilkS")
		)
		(fp_line
			(start -0.67945 0.3048)
			(end -0.67945 -0.305054)
			(stroke
				(width 0.1)
				(type default)
			)
			(layer "F.Fab")
		)
		(fp_line
			(start -0.12065 0.3048)
			(end -0.67945 0.3048)
			(stroke
				(width 0.1)
				(type default)
			)
			(layer "F.Fab")
		)
		(fp_line
			(start 0.120396 0.3048)
			(end 0.120396 0.2794)
			(stroke
				(width 0.1)
				(type default)
			)
			(layer "F.Fab")
		)
		(fp_line
			(start 0.67945 0.3048)
			(end 0.120396 0.3048)
			(stroke
				(width 0.1)
				(type default)
			)
			(layer "F.Fab")
		)
		(fp_line
			(start -0.12065 0.2794)
			(end -0.12065 0.3048)
			(stroke
				(width 0.1)
				(type default)
			)
			(layer "F.Fab")
		)
		(fp_line
			(start 0.120396 0.2794)
			(end -0.12065 0.2794)
			(stroke
				(width 0.1)
				(type default)
			)
			(layer "F.Fab")
		)
		(fp_line
			(start -0.12065 -0.2794)
			(end 0.12065 -0.2794)
			(stroke
				(width 0.1)
				(type default)
			)
			(layer "F.Fab")
		)
		(fp_line
			(start 0.12065 -0.2794)
			(end 0.12065 -0.3048)
			(stroke
				(width 0.1)
				(type default)
			)
			(layer "F.Fab")
		)
		(fp_line
			(start 0.12065 -0.3048)
			(end 0.67945 -0.3048)
			(stroke
				(width 0.1)
				(type default)
			)
			(layer "F.Fab")
		)
		(fp_line
			(start 0.67945 -0.3048)
			(end 0.67945 0.3048)
			(stroke
				(width 0.1)
				(type default)
			)
			(layer "F.Fab")
		)
		(fp_line
			(start -0.67945 -0.305054)
			(end -0.12065 -0.305054)
			(stroke
				(width 0.1)
				(type default)
			)
			(layer "F.Fab")
		)
		(fp_line
			(start -0.12065 -0.305054)
			(end -0.12065 -0.2794)
			(stroke
				(width 0.1)
				(type default)
			)
			(layer "F.Fab")
		)
		(pad "1" smd circle
			(at -0.40005 0 270)
			(size 0 0)
			(layers "F.Cu" "F.Mask" "F.Paste")
			(net "PVDDCR_CPU1_P1_PVCC")
		)
		(pad "2" smd circle
			(at 0.40005 0 270)
			(size 0 0)
			(layers "F.Cu" "F.Mask" "F.Paste")
			(net "GND")
		)
	)
	(footprint ""
		(layer "F.Cu")
		(at 122.80011 -146.957288)
		(property "Reference" "PC6007"
			(at 0 0 0)
			(layer "F.SilkS")
			(hide yes)
			(effects
				(font
					(size 1.27 1.27)
				)
			)
		)
		(property "Value" ""
			(at 0 0 0)
			(layer "F.Fab")
			(effects
				(font
					(size 1.27 1.27)
				)
			)
		)
		(duplicate_pad_numbers_are_jumpers no)
		(fp_line
			(start -0.7874 -0.4064)
			(end 0.7874 -0.4064)
			(stroke
				(width 0.1524)
				(type default)
			)
			(layer "F.SilkS")
		)
		(fp_line
			(start -0.7874 0.4064)
			(end -0.7874 -0.4064)
			(stroke
				(width 0.1524)
				(type default)
			)
			(layer "F.SilkS")
		)
		(fp_line
			(start 0.7874 -0.4064)
			(end 0.7874 0.4064)
			(stroke
				(width 0.1524)
				(type default)
			)
			(layer "F.SilkS")
		)
		(fp_line
			(start 0.7874 0.4064)
			(end -0.7874 0.4064)
			(stroke
				(width 0.1524)
				(type default)
			)
			(layer "F.SilkS")
		)
		(fp_line
			(start -0.67945 -0.305054)
			(end -0.12065 -0.305054)
			(stroke
				(width 0.1)
				(type default)
			)
			(layer "F.Fab")
		)
		(fp_line
			(start -0.67945 0.3048)
			(end -0.67945 -0.305054)
			(stroke
				(width 0.1)
				(type default)
			)
			(layer "F.Fab")
		)
		(fp_line
			(start -0.12065 -0.305054)
			(end -0.12065 -0.2794)
			(stroke
				(width 0.1)
				(type default)
			)
			(layer "F.Fab")
		)
		(fp_line
			(start -0.12065 -0.2794)
			(end 0.12065 -0.2794)
			(stroke
				(width 0.1)
				(type default)
			)
			(layer "F.Fab")
		)
		(fp_line
			(start -0.12065 0.2794)
			(end -0.12065 0.3048)
			(stroke
				(width 0.1)
				(type default)
			)
			(layer "F.Fab")
		)
		(fp_line
			(start -0.12065 0.3048)
			(end -0.67945 0.3048)
			(stroke
				(width 0.1)
				(type default)
			)
			(layer "F.Fab")
		)
		(fp_line
			(start 0.120396 0.2794)
			(end -0.12065 0.2794)
			(stroke
				(width 0.1)
				(type default)
			)
			(layer "F.Fab")
		)
		(fp_line
			(start 0.120396 0.3048)
			(end 0.120396 0.2794)
			(stroke
				(width 0.1)
				(type default)
			)
			(layer "F.Fab")
		)
		(fp_line
			(start 0.12065 -0.3048)
			(end 0.67945 -0.3048)
			(stroke
				(width 0.1)
				(type default)
			)
			(layer "F.Fab")
		)
		(fp_line
			(start 0.12065 -0.2794)
			(end 0.12065 -0.3048)
			(stroke
				(width 0.1)
				(type default)
			)
			(layer "F.Fab")
		)
		(fp_line
			(start 0.67945 -0.3048)
			(end 0.67945 0.3048)
			(stroke
				(width 0.1)
				(type default)
			)
			(layer "F.Fab")
		)
		(fp_line
			(start 0.67945 0.3048)
			(end 0.120396 0.3048)
			(stroke
				(width 0.1)
				(type default)
			)
			(layer "F.Fab")
		)
		(pad "1" smd circle
			(at -0.40005 0)
			(size 0 0)
			(layers "F.Cu" "F.Mask" "F.Paste")
			(net "P12V_AUX")
		)
		(pad "2" smd circle
			(at 0.40005 0)
			(size 0 0)
			(layers "F.Cu" "F.Mask" "F.Paste")
			(net "GND")
		)
	)
)
